# S9S_MB_2U (Grand Teton) — schematic netlist excerpt (pin names and nets, part order shuffled) for the footprints in the layout excerpt that follows; sources: Cadence DE-HDL packaged netlist, KiCad conversion of 03242023_DA0F0TMBIJ0_F0T_Motherboard_J_brd_V01_OCP.brd

U320  74LVC1G66GV  IC  pkg SC74AXA  page 155
  Y  = CLK_50M_NCSI_OCP_SFF
  Z  = CLK_50M_NCSI_OCP_SFF_ISO_R
  GND  = GND
  E  = FB_BMC_ISOLATE
  VCC  = P3V3_AUX

R3760  Q_RES  10 1% CHIP  pkg 0402LF  page 171 : A = P3V3_E1S_0 ; B = VSENSE_P3V3_INA230_2_INN

(kicad_pcb
	(version 20260206)
	(generator "pcbnew")
	(generator_version "10.0")
	(general
		(thickness 1.6)
		(legacy_teardrops no)
	)
	(paper "A4")
	(title_block
		(title "03242023_DA0F0TMBIJ0_F0T_Motherboard_J_brd_V01_OCP.brd")
		(comment 1 "Grand Teton / footprints 1559-1560 of 6105")
	)
	(layers
		(0 "F.Cu" signal "TOP")
		(4 "In1.Cu" signal "GND")
		(6 "In2.Cu" signal "IN1")
		(8 "In3.Cu" signal "GND1")
		(10 "In4.Cu" signal "IN2")
		(12 "In5.Cu" signal "GND2")
		(14 "In6.Cu" signal "IN3")
		(16 "In7.Cu" signal "GND3")
		(18 "In8.Cu" signal "VCC")
		(20 "In9.Cu" signal "VCC1")
		(22 "In10.Cu" signal "GND4")
		(24 "In11.Cu" signal "IN4")
		(26 "In12.Cu" signal "GND5")
		(28 "In13.Cu" signal "IN5")
		(30 "In14.Cu" signal "GND6")
		(32 "In15.Cu" signal "IN6")
		(34 "In16.Cu" signal "GND7")
		(2 "B.Cu" signal "BOTTOM")
		(9 "F.Adhes" user "F.Adhesive")
		(11 "B.Adhes" user "B.Adhesive")
		(13 "F.Paste" user "Package Geometry/Pastemask Top")
		(15 "B.Paste" user "Package Geometry/Pastemask Bottom")
		(5 "F.SilkS" user "Ref Des/Silkscreen Top")
		(7 "B.SilkS" user "Ref Des/Silkscreen Bottom")
		(1 "F.Mask" user "Board Geometry/Soldermask Top")
		(3 "B.Mask" user "Board Geometry/Soldermask Bottom")
		(17 "Dwgs.User" user "User.Drawings")
		(19 "Cmts.User" user "User.Comments")
		(21 "Eco1.User" user "User.Eco1")
		(23 "Eco2.User" user "User.Eco2")
		(25 "Edge.Cuts" user "Board Geometry/Outline")
		(27 "Margin" user)
		(31 "F.CrtYd" user "Package Geometry/Place Bound Top")
		(29 "B.CrtYd" user "Package Geometry/Place Bound Bottom")
		(35 "F.Fab" user "Ref Des/Assembly Top")
		(33 "B.Fab" user "Ref Des/Assembly Bottom")
	)
	(footprint ""
		(layer "F.Cu")
		(at 369.6208 -16.271748 180)
		(property "Reference" "U320"
			(at 1.64338 -2.461768 0)
			(unlocked yes)
			(layer "F.SilkS")
			(effects
				(font
					(size 0.7874 0.5842)
					(thickness 0.1524)
				)
				(justify left)
			)
		)
		(property "Value" ""
			(at 0 0 180)
			(layer "F.Fab")
			(effects
				(font
					(size 1.27 1.27)
				)
			)
		)
		(duplicate_pad_numbers_are_jumpers no)
		(fp_line
			(start 2.032 1.549908)
			(end -2.032 1.549908)
			(stroke
				(width 0.1524)
				(type default)
			)
			(layer "F.SilkS")
		)
		(fp_line
			(start 2.032 -1.549908)
			(end 2.032 1.549908)
			(stroke
				(width 0.1524)
				(type default)
			)
			(layer "F.SilkS")
		)
		(fp_line
			(start -2.032 1.549908)
			(end -2.032 -1.549908)
			(stroke
				(width 0.1524)
				(type default)
			)
			(layer "F.SilkS")
		)
		(fp_line
			(start -2.032 -1.549908)
			(end 2.032 -1.549908)
			(stroke
				(width 0.1524)
				(type default)
			)
			(layer "F.SilkS")
		)
		(fp_poly
			(pts
				(xy -2.629408 -2.512568) (xy -2.988564 -2.153412) (xy -2.270252 -1.794002)
			)
			(stroke
				(width 0)
				(type default)
			)
			(fill yes)
			(layer "F.SilkS")
		)
		(fp_line
			(start 0.849884 1.549908)
			(end 0.849884 -1.549908)
			(stroke
				(width 0.1)
				(type default)
			)
			(layer "F.Fab")
		)
		(fp_line
			(start 0.849884 -1.549908)
			(end -0.849884 -1.549908)
			(stroke
				(width 0.1)
				(type default)
			)
			(layer "F.Fab")
		)
		(fp_line
			(start -0.849884 1.549908)
			(end 0.849884 1.549908)
			(stroke
				(width 0.1)
				(type default)
			)
			(layer "F.Fab")
		)
		(fp_line
			(start -0.849884 -1.549908)
			(end -0.849884 1.549908)
			(stroke
				(width 0.1)
				(type default)
			)
			(layer "F.Fab")
		)
		(fp_poly
			(pts
				(xy -2.9464 -1.2192) (xy -2.9464 -0.7112) (xy -2.1844 -0.9652)
			)
			(stroke
				(width 0)
				(type default)
			)
			(fill yes)
			(layer "F.Fab")
		)
		(pad "1" smd rect
			(at -1.225042 -0.94996 90)
			(size 0.4572 1.3208)
			(layers "F.Cu" "F.Mask" "F.Paste")
			(net "CLK_50M_NCSI_OCP_SFF")
		)
		(pad "2" smd rect
			(at -1.225042 0 90)
			(size 0.4572 1.3208)
			(layers "F.Cu" "F.Mask" "F.Paste")
			(net "CLK_50M_NCSI_OCP_SFF_ISO_R")
		)
		(pad "3" smd rect
			(at -1.225042 0.94996 90)
			(size 0.4572 1.3208)
			(layers "F.Cu" "F.Mask" "F.Paste")
			(net "GND")
		)
		(pad "4" smd rect
			(at 1.225042 0.94996 90)
			(size 0.4572 1.3208)
			(layers "F.Cu" "F.Mask" "F.Paste")
			(net "FB_BMC_ISOLATE")
		)
		(pad "5" smd rect
			(at 1.225042 -0.94996 90)
			(size 0.4572 1.3208)
			(layers "F.Cu" "F.Mask" "F.Paste")
			(net "P3V3_AUX")
		)
	)
	(footprint ""
		(layer "F.Cu")
		(at 220.190822 -56.835802 180)
		(property "Reference" "R3760"
			(at 0 0 180)
			(layer "F.SilkS")
			(hide yes)
			(effects
				(font
					(size 1.27 1.27)
				)
			)
		)
		(property "Value" ""
			(at 0 0 180)
			(layer "F.Fab")
			(effects
				(font
					(size 1.27 1.27)
				)
			)
		)
		(duplicate_pad_numbers_are_jumpers no)
		(fp_line
			(start 0.7874 0.4064)
			(end -0.7874 0.4064)
			(stroke
				(width 0.1524)
				(type default)
			)
			(layer "F.SilkS")
		)
		(fp_line
			(start 0.7874 -0.4064)
			(end 0.7874 0.4064)
			(stroke
				(width 0.1524)
				(type default)
			)
			(layer "F.SilkS")
		)
		(fp_line
			(start -0.7874 0.4064)
			(end -0.7874 -0.4064)
			(stroke
				(width 0.1524)
				(type default)
			)
			(layer "F.SilkS")
		)
		(fp_line
			(start -0.7874 -0.4064)
			(end 0.7874 -0.4064)
			(stroke
				(width 0.1524)
				(type default)
			)
			(layer "F.SilkS")
		)
		(fp_line
			(start 0.67945 0.3048)
			(end 0.120396 0.3048)
			(stroke
				(width 0.1)
				(type default)
			)
			(layer "F.Fab")
		)
		(fp_line
			(start 0.67945 -0.3048)
			(end 0.67945 0.3048)
			(stroke
				(width 0.1)
				(type default)
			)
			(layer "F.Fab")
		)
		(fp_line
			(start 0.12065 -0.2794)
			(end 0.12065 -0.3048)
			(stroke
				(width 0.1)
				(type default)
			)
			(layer "F.Fab")
		)
		(fp_line
			(start 0.12065 -0.3048)
			(end 0.67945 -0.3048)
			(stroke
				(width 0.1)
				(type default)
			)
			(layer "F.Fab")
		)
		(fp_line
			(start 0.120396 0.3048)
			(end 0.120396 0.2794)
			(stroke
				(width 0.1)
				(type default)
			)
			(layer "F.Fab")
		)
		(fp_line
			(start 0.120396 0.2794)
			(end -0.12065 0.2794)
			(stroke
				(width 0.1)
				(type default)
			)
			(layer "F.Fab")
		)
		(fp_line
			(start -0.12065 0.3048)
			(end -0.67945 0.3048)
			(stroke
				(width 0.1)
				(type default)
			)
			(layer "F.Fab")
		)
		(fp_line
			(start -0.12065 0.2794)
			(end -0.12065 0.3048)
			(stroke
				(width 0.1)
				(type default)
			)
			(layer "F.Fab")
		)
		(fp_line
			(start -0.12065 -0.2794)
			(end 0.12065 -0.2794)
			(stroke
				(width 0.1)
				(type default)
			)
			(layer "F.Fab")
		)
		(fp_line
			(start -0.12065 -0.305054)
			(end -0.12065 -0.2794)
			(stroke
				(width 0.1)
				(type default)
			)
			(layer "F.Fab")
		)
		(fp_line
			(start -0.67945 0.3048)
			(end -0.67945 -0.305054)
			(stroke
				(width 0.1)
				(type default)
			)
			(layer "F.Fab")
		)
		(fp_line
			(start -0.67945 -0.305054)
			(end -0.12065 -0.305054)
			(stroke
				(width 0.1)
				(type default)
			)
			(layer "F.Fab")
		)
		(pad "1" smd circle
			(at -0.40005 0 180)
			(size 0 0)
			(layers "F.Cu" "F.Mask" "F.Paste")
			(net "P3V3_E1S_0")
		)
		(pad "2" smd circle
			(at 0.40005 0 180)
			(size 0 0)
			(layers "F.Cu" "F.Mask" "F.Paste")
			(net "VSENSE_P3V3_INA230_2_INN")
		)
	)
)
